# TIMECARD (Time Appliance Project (Time Card)) — schematic netlist excerpt (pin names and nets, part order shuffled) for the footprints in the layout excerpt that follows; sources: Cadence DE-HDL packaged netlist, KiCad conversion of R4006-B0001-02_R01.brd

C94  CAPACITOR  0.1UF 25V 10%  pkg SMC_0402R_H022  page 24 : \1\ = XP5R0V_FT4232 ; \2\ = SG
R54  RESISTOR  0OHM -  pkg SMC_0603R_H024  page 28 : \1\ = XP3R3V_AGND ; \2\ = XP3R3V_FB_R_TO_AGND

(kicad_pcb
	(version 20260206)
	(generator "pcbnew")
	(generator_version "10.0")
	(general
		(thickness 1.6)
		(legacy_teardrops no)
	)
	(paper "A4")
	(title_block
		(title "timecard-production-celestica-r4006 — R4006-B0001-02_R01.brd")
		(comment 1 "Time Appliance Project (Time Card) / footprints 995-996 of 1113")
	)
	(layers
		(0 "F.Cu" signal "TOP")
		(4 "In1.Cu" signal "L02_GND1")
		(6 "In2.Cu" signal "L03_SIG1")
		(8 "In3.Cu" signal "L04_GND2")
		(10 "In4.Cu" signal "L05_VCC1")
		(12 "In5.Cu" signal "L06_VCC2")
		(14 "In6.Cu" signal "L07_GND3")
		(16 "In7.Cu" signal "L08_SIG2")
		(18 "In8.Cu" signal "L09_GND4")
		(2 "B.Cu" signal "BOTTOM")
		(9 "F.Adhes" user "F.Adhesive")
		(11 "B.Adhes" user "B.Adhesive")
		(13 "F.Paste" user "Package Geometry/Pastemask Top")
		(15 "B.Paste" user "Package Geometry/Pastemask Bottom")
		(5 "F.SilkS" user "Ref Des/Silkscreen Top")
		(7 "B.SilkS" user "Ref Des/Silkscreen Bottom")
		(1 "F.Mask" user "Board Geometry/Soldermask Top")
		(3 "B.Mask" user "Board Geometry/Soldermask Bottom")
		(17 "Dwgs.User" user "User.Drawings")
		(19 "Cmts.User" user "User.Comments")
		(21 "Eco1.User" user "User.Eco1")
		(23 "Eco2.User" user "User.Eco2")
		(25 "Edge.Cuts" user "Board Geometry/Outline")
		(27 "Margin" user)
		(31 "F.CrtYd" user "Package Geometry/Place Bound Top")
		(29 "B.CrtYd" user "Package Geometry/Place Bound Bottom")
		(35 "F.Fab" user "Ref Des/Assembly Top")
		(33 "B.Fab" user "Ref Des/Assembly Bottom")
	)
	(footprint ""
		(layer "B.Cu")
		(at 17.78 -86.487 90)
		(property "Reference" "C94"
			(at 0.127 1.23063 270)
			(unlocked yes)
			(layer "B.SilkS")
			(effects
				(font
					(size 0.7874 0.5842)
					(thickness 0.1524)
				)
				(justify mirror)
			)
		)
		(property "Value" "VAL*"
			(at -0.0762 2.067306 90)
			(unlocked yes)
			(layer "B.Fab")
			(hide yes)
			(effects
				(font
					(size 0.7874 0.5842)
					(thickness 0.1524)
				)
				(justify mirror)
			)
		)
		(property "Tolerance" "TOL*"
			(at -0.0762 3.032506 90)
			(unlocked yes)
			(layer "Cmts.User")
			(hide yes)
			(effects
				(font
					(size 0.7874 0.5842)
					(thickness 0.1524)
				)
				(justify mirror)
			)
		)
		(property "User Part Number" "PARTNUM*"
			(at -0.1016 4.023106 90)
			(unlocked yes)
			(layer "Cmts.User")
			(hide yes)
			(effects
				(font
					(size 0.7874 0.5842)
					(thickness 0.1524)
				)
				(justify mirror)
			)
		)
		(property "Device Type" "CAPACITOR-G105-0B104-EK,0.1UF,A"
			(at -0.0508 1.127506 90)
			(unlocked yes)
			(layer "B.Fab")
			(hide yes)
			(effects
				(font
					(size 0.7874 0.5842)
					(thickness 0.1524)
				)
				(justify mirror)
			)
		)
		(duplicate_pad_numbers_are_jumpers no)
		(fp_line
			(start 1.143 -0.5588)
			(end 1.143 0.5588)
			(stroke
				(width 0.1)
				(type default)
			)
			(layer "B.SilkS")
		)
		(fp_line
			(start -1.143 -0.5588)
			(end 1.143 -0.5588)
			(stroke
				(width 0.1)
				(type default)
			)
			(layer "B.SilkS")
		)
		(fp_line
			(start 1.143 0.5588)
			(end -1.143 0.5588)
			(stroke
				(width 0.1)
				(type default)
			)
			(layer "B.SilkS")
		)
		(fp_line
			(start -1.143 0.5588)
			(end -1.143 -0.5588)
			(stroke
				(width 0.1)
				(type default)
			)
			(layer "B.SilkS")
		)
		(fp_poly
			(pts
				(xy 1.143 0.5588) (xy -1.143 0.5588) (xy -1.143 -0.5588) (xy 1.143 -0.5588)
			)
			(stroke
				(width 0)
				(type default)
			)
			(fill no)
			(layer "B.CrtYd")
		)
		(fp_line
			(start 0.508 -0.3048)
			(end 0.508 0.3048)
			(stroke
				(width 0.1)
				(type default)
			)
			(layer "B.Fab")
		)
		(fp_line
			(start -0.508 -0.3048)
			(end 0.508 -0.3048)
			(stroke
				(width 0.1)
				(type default)
			)
			(layer "B.Fab")
		)
		(fp_line
			(start 0.508 0.3048)
			(end -0.508 0.3048)
			(stroke
				(width 0.1)
				(type default)
			)
			(layer "B.Fab")
		)
		(fp_line
			(start -0.508 0.3048)
			(end -0.508 -0.3048)
			(stroke
				(width 0.1)
				(type default)
			)
			(layer "B.Fab")
		)
		(pad "1" smd rect
			(at 0.5334 0 270)
			(size 0.7112 0.6096)
			(layers "B.Cu" "B.Mask" "B.Paste")
			(net "XP5R0V_FT4232")
		)
		(pad "2" smd rect
			(at -0.5334 0 270)
			(size 0.7112 0.6096)
			(layers "B.Cu" "B.Mask" "B.Paste")
			(net "SG")
		)
		(zone
			(layer "B.Cu")
			(hatch none 0.5)
			(connect_pads
				(clearance 0)
			)
			(min_thickness 0.25)
			(keepout
				(tracks not_allowed)
				(vias allowed)
				(pads allowed)
				(copperpour not_allowed)
				(footprints allowed)
			)
			(placement
				(enabled no)
				(sheetname "")
			)
			(fill
				(thermal_gap 0.5)
				(thermal_bridge_width 0.5)
				(island_removal_mode 0)
			)
			(polygon
				(pts
					(xy 18.0848 -86.5632) (xy 17.4752 -86.5632) (xy 17.4752 -86.4108) (xy 18.0848 -86.4108)
				)
			)
		)
		(zone
			(layer "B.Cu")
			(hatch none 0.5)
			(connect_pads
				(clearance 0)
			)
			(min_thickness 0.25)
			(keepout
				(tracks allowed)
				(vias not_allowed)
				(pads allowed)
				(copperpour not_allowed)
				(footprints allowed)
			)
			(placement
				(enabled no)
				(sheetname "")
			)
			(fill
				(thermal_gap 0.5)
				(thermal_bridge_width 0.5)
				(island_removal_mode 0)
			)
			(polygon
				(pts
					(xy 18.0848 -86.5632) (xy 17.4752 -86.5632) (xy 17.4752 -86.4108) (xy 18.0848 -86.4108)
				)
			)
		)
	)
	(footprint ""
		(layer "B.Cu")
		(at 89.9922 -98.7298)
		(property "Reference" "R54"
			(at 3.683 0.03937 0)
			(unlocked yes)
			(layer "B.SilkS")
			(effects
				(font
					(size 0.7874 0.5842)
					(thickness 0.1524)
				)
				(justify mirror)
			)
		)
		(property "Value" "VAL*"
			(at 0.0254 2.524506 0)
			(unlocked yes)
			(layer "B.Fab")
			(hide yes)
			(effects
				(font
					(size 0.7874 0.5842)
					(thickness 0.1524)
				)
				(justify mirror)
			)
		)
		(property "Tolerance" "TOL*"
			(at 0.0254 3.464306 0)
			(unlocked yes)
			(layer "Cmts.User")
			(hide yes)
			(effects
				(font
					(size 0.7874 0.5842)
					(thickness 0.1524)
				)
				(justify mirror)
			)
		)
		(property "User Part Number" "PARTNUM*"
			(at 0.0254 4.505706 0)
			(unlocked yes)
			(layer "Cmts.User")
			(hide yes)
			(effects
				(font
					(size 0.7874 0.5842)
					(thickness 0.1524)
				)
				(justify mirror)
			)
		)
		(property "Device Type" "RESISTOR-G156-100R0-J0,0OHM,-"
			(at 0 1.610106 0)
			(unlocked yes)
			(layer "B.Fab")
			(hide yes)
			(effects
				(font
					(size 0.7874 0.5842)
					(thickness 0.1524)
				)
				(justify mirror)
			)
		)
		(duplicate_pad_numbers_are_jumpers no)
		(fp_line
			(start -1.3208 -0.7112)
			(end -1.3208 0.7112)
			(stroke
				(width 0.1)
				(type default)
			)
			(layer "B.SilkS")
		)
		(fp_line
			(start -1.3208 0.7112)
			(end 1.3208 0.7112)
			(stroke
				(width 0.1)
				(type default)
			)
			(layer "B.SilkS")
		)
		(fp_line
			(start 1.3208 -0.7112)
			(end -1.3208 -0.7112)
			(stroke
				(width 0.1)
				(type default)
			)
			(layer "B.SilkS")
		)
		(fp_line
			(start 1.3208 0.7112)
			(end 1.3208 -0.7112)
			(stroke
				(width 0.1)
				(type default)
			)
			(layer "B.SilkS")
		)
		(fp_rect
			(start -1.3208 0.7112)
			(end 1.3208 -0.7112)
			(stroke
				(width 0)
				(type default)
			)
			(fill no)
			(layer "B.CrtYd")
		)
		(fp_line
			(start -0.8128 -0.4572)
			(end -0.8128 0.4572)
			(stroke
				(width 0.1)
				(type default)
			)
			(layer "B.Fab")
		)
		(fp_line
			(start -0.8128 0.4572)
			(end 0.8128 0.4572)
			(stroke
				(width 0.1)
				(type default)
			)
			(layer "B.Fab")
		)
		(fp_line
			(start 0.8128 -0.4572)
			(end -0.8128 -0.4572)
			(stroke
				(width 0.1)
				(type default)
			)
			(layer "B.Fab")
		)
		(fp_line
			(start 0.8128 0.4572)
			(end 0.8128 -0.4572)
			(stroke
				(width 0.1)
				(type default)
			)
			(layer "B.Fab")
		)
		(pad "1" smd rect
			(at 0.6858 0 180)
			(size 0.762 0.8636)
			(layers "B.Cu" "B.Mask" "B.Paste")
			(net "XP3R3V_AGND")
		)
		(pad "2" smd rect
			(at -0.6858 0 180)
			(size 0.762 0.8636)
			(layers "B.Cu" "B.Mask" "B.Paste")
			(net "XP3R3V_FB_R_TO_AGND")
		)
		(zone
			(layer "B.Cu")
			(hatch none 0.5)
			(connect_pads
				(clearance 0)
			)
			(min_thickness 0.25)
			(keepout
				(tracks allowed)
				(vias not_allowed)
				(pads allowed)
				(copperpour not_allowed)
				(footprints allowed)
			)
			(placement
				(enabled no)
				(sheetname "")
			)
			(fill
				(thermal_gap 0.5)
				(thermal_bridge_width 0.5)
				(island_removal_mode 0)
			)
			(polygon
				(pts
					(xy 89.8398 -98.2726) (xy 90.1446 -98.2726) (xy 90.1446 -99.187) (xy 89.8398 -99.187)
				)
			)
		)
	)
)
